#ISCELL
  mstr_symbols cad_note *
  *
#ISCELL
  mstr_symbols intel_corp_bpage *
  *
#ISCELL
  mstr_standard offpage *
  page100_i1
#ISCELL
  mstr_symbols pvddq_klm *
  page100_i10
#CELL
  mstr_discrete res *
  page100_i11
#ISCELL
  mstr_standard offpage *
  page100_i12
#CELL
  mstr_discrete res *
  page100_i13
#ISCELL
  mstr_symbols gnd *
  page100_i14
#CELL
  dev_discrete cap_a *
  page100_i15
#ISCELL
  mstr_standard offpage *
  page100_i16
#ISCELL
  mstr_symbols pvddq_ghj *
  page100_i17
#ISCELL
  mstr_standard offpage *
  page100_i18
#CELL
  mstr_discrete res *
  page100_i19
#CELL
  mstr_discrete res *
  page100_i2
#CELL
  mstr_discrete res *
  page100_i20
#ISCELL
  mstr_symbols pvddq_klm *
  page100_i21
#CELL
  mstr_discrete res *
  page100_i22
#ISCELL
  mstr_standard offpage *
  page100_i23
#CELL
  mstr_discrete res *
  page100_i24
#CELL
  mstr_discrete res *
  page100_i25
#CELL
  dev_discrete cap_a *
  page100_i26
#ISCELL
  mstr_standard offpage *
  page100_i27
#ISCELL
  mstr_symbols gnd *
  page100_i28
#CELL
  mstr_discrete res *
  page100_i29
#ISCELL
  mstr_standard offpage *
  page100_i3
#CELL
  dev_discrete cap_a *
  page100_i30
#ISCELL
  mstr_symbols gnd *
  page100_i31
#ISCELL
  mstr_standard offpage *
  page100_i32
#ISCELL
  mstr_symbols pvddq_ghj *
  page100_i33
#ISCELL
  mstr_standard offpage *
  page100_i34
#CELL
  mstr_discrete res *
  page100_i35
#CELL
  mstr_discrete res *
  page100_i36
#ISCELL
  mstr_symbols pvddq_klm *
  page100_i37
#CELL
  mstr_discrete res *
  page100_i38
#ISCELL
  mstr_standard offpage *
  page100_i39
#CELL
  mstr_discrete res *
  page100_i4
#CELL
  mstr_discrete res *
  page100_i40
#CELL
  mstr_discrete res *
  page100_i41
#CELL
  dev_discrete cap_a *
  page100_i42
#ISCELL
  mstr_standard offpage *
  page100_i43
#ISCELL
  mstr_symbols gnd *
  page100_i44
#CELL
  mstr_discrete res *
  page100_i45
#CELL
  dev_discrete cap_a *
  page100_i46
#ISCELL
  mstr_symbols gnd *
  page100_i47
#ISCELL
  mstr_standard offpage *
  page100_i48
#ISCELL
  mstr_symbols pvddq_ghj *
  page100_i5
#CELL
  mstr_discrete res *
  page100_i6
#CELL
  mstr_discrete res *
  page100_i7
#CELL
  dev_discrete cap_a *
  page100_i8
#ISCELL
  mstr_symbols gnd *
  page100_i9
